# TIMECARD (Time Appliance Project (Time Card)) — schematic netlist excerpt (pin names and nets, part order shuffled) for the footprints in the layout excerpt that follows; sources: Cadence DE-HDL packaged netlist, KiCad conversion of R4006-B0001-02_R01.brd

R448  RESISTOR  33OHM 1%  pkg SMC_0402R_H016  page 24 : \1\ = MUX1_SEL ; \2\ = FPGA_OUT_MUX1_SEL
R1992  RESISTOR  4.7KOHM 1%  pkg SMC_0402R_H016  page 16 : \1\ = XP3R3V_FPGA ; \2\ = SN_EEPROM_WP

(kicad_pcb
	(version 20260206)
	(generator "pcbnew")
	(generator_version "10.0")
	(general
		(thickness 1.6)
		(legacy_teardrops no)
	)
	(paper "A4")
	(title_block
		(title "timecard-production-celestica-r4006 — R4006-B0001-02_R01.brd")
		(comment 1 "Time Appliance Project (Time Card) / footprints 74-75 of 1113")
	)
	(layers
		(0 "F.Cu" signal "TOP")
		(4 "In1.Cu" signal "L02_GND1")
		(6 "In2.Cu" signal "L03_SIG1")
		(8 "In3.Cu" signal "L04_GND2")
		(10 "In4.Cu" signal "L05_VCC1")
		(12 "In5.Cu" signal "L06_VCC2")
		(14 "In6.Cu" signal "L07_GND3")
		(16 "In7.Cu" signal "L08_SIG2")
		(18 "In8.Cu" signal "L09_GND4")
		(2 "B.Cu" signal "BOTTOM")
		(9 "F.Adhes" user "F.Adhesive")
		(11 "B.Adhes" user "B.Adhesive")
		(13 "F.Paste" user "Package Geometry/Pastemask Top")
		(15 "B.Paste" user "Package Geometry/Pastemask Bottom")
		(5 "F.SilkS" user "Ref Des/Silkscreen Top")
		(7 "B.SilkS" user "Ref Des/Silkscreen Bottom")
		(1 "F.Mask" user "Board Geometry/Soldermask Top")
		(3 "B.Mask" user "Board Geometry/Soldermask Bottom")
		(17 "Dwgs.User" user "User.Drawings")
		(19 "Cmts.User" user "User.Comments")
		(21 "Eco1.User" user "User.Eco1")
		(23 "Eco2.User" user "User.Eco2")
		(25 "Edge.Cuts" user "Board Geometry/Outline")
		(27 "Margin" user)
		(31 "F.CrtYd" user "Package Geometry/Place Bound Top")
		(29 "B.CrtYd" user "Package Geometry/Place Bound Bottom")
		(35 "F.Fab" user "Ref Des/Assembly Top")
		(33 "B.Fab" user "Ref Des/Assembly Bottom")
	)
	(footprint ""
		(layer "F.Cu")
		(at 98.044 -96.774 180)
		(property "Reference" "R448"
			(at 1.143 2.75463 0)
			(unlocked yes)
			(layer "F.SilkS")
			(effects
				(font
					(size 0.7874 0.5842)
					(thickness 0.1524)
				)
			)
		)
		(property "Value" "VAL*"
			(at 0.02032 2.13233 180)
			(unlocked yes)
			(layer "F.Fab")
			(hide yes)
			(effects
				(font
					(size 0.7874 0.5842)
					(thickness 0.1524)
				)
			)
		)
		(property "Tolerance" "TOL*"
			(at 0.044704 3.05435 180)
			(unlocked yes)
			(layer "Cmts.User")
			(hide yes)
			(effects
				(font
					(size 0.7874 0.5842)
					(thickness 0.1524)
				)
			)
		)
		(property "User Part Number" "PARTNUM*"
			(at 0.02032 4.024884 180)
			(unlocked yes)
			(layer "Cmts.User")
			(hide yes)
			(effects
				(font
					(size 0.7874 0.5842)
					(thickness 0.1524)
				)
			)
		)
		(property "Device Type" "RESISTOR-G155-133R0-01,33OHM,1%"
			(at 0.008382 1.210564 180)
			(unlocked yes)
			(layer "F.Fab")
			(hide yes)
			(effects
				(font
					(size 0.7874 0.5842)
					(thickness 0.1524)
				)
			)
		)
		(duplicate_pad_numbers_are_jumpers no)
		(fp_line
			(start 1.143 0.5588)
			(end 1.143 -0.5588)
			(stroke
				(width 0.1)
				(type default)
			)
			(layer "F.SilkS")
		)
		(fp_line
			(start 1.143 -0.5588)
			(end -1.143 -0.5588)
			(stroke
				(width 0.1)
				(type default)
			)
			(layer "F.SilkS")
		)
		(fp_line
			(start -1.143 0.5588)
			(end 1.143 0.5588)
			(stroke
				(width 0.1)
				(type default)
			)
			(layer "F.SilkS")
		)
		(fp_line
			(start -1.143 -0.5588)
			(end -1.143 0.5588)
			(stroke
				(width 0.1)
				(type default)
			)
			(layer "F.SilkS")
		)
		(fp_poly
			(pts
				(xy -1.143 0.5588) (xy 1.143 0.5588) (xy 1.143 -0.5588) (xy -1.143 -0.5588)
			)
			(stroke
				(width 0)
				(type default)
			)
			(fill no)
			(layer "F.CrtYd")
		)
		(fp_line
			(start 0.508 0.3048)
			(end 0.508 -0.3048)
			(stroke
				(width 0.1)
				(type default)
			)
			(layer "F.Fab")
		)
		(fp_line
			(start 0.508 -0.3048)
			(end -0.508 -0.3048)
			(stroke
				(width 0.1)
				(type default)
			)
			(layer "F.Fab")
		)
		(fp_line
			(start -0.508 0.3048)
			(end 0.508 0.3048)
			(stroke
				(width 0.1)
				(type default)
			)
			(layer "F.Fab")
		)
		(fp_line
			(start -0.508 -0.3048)
			(end -0.508 0.3048)
			(stroke
				(width 0.1)
				(type default)
			)
			(layer "F.Fab")
		)
		(pad "1" smd rect
			(at -0.5334 0 180)
			(size 0.7112 0.6096)
			(layers "F.Cu" "F.Mask" "F.Paste")
			(net "MUX1_SEL")
		)
		(pad "2" smd rect
			(at 0.5334 0 180)
			(size 0.7112 0.6096)
			(layers "F.Cu" "F.Mask" "F.Paste")
			(net "FPGA_OUT_MUX1_SEL")
		)
		(zone
			(layer "F.Cu")
			(hatch none 0.5)
			(connect_pads
				(clearance 0)
			)
			(min_thickness 0.25)
			(keepout
				(tracks allowed)
				(vias not_allowed)
				(pads allowed)
				(copperpour not_allowed)
				(footprints allowed)
			)
			(placement
				(enabled no)
				(sheetname "")
			)
			(fill
				(thermal_gap 0.5)
				(thermal_bridge_width 0.5)
				(island_removal_mode 0)
			)
			(polygon
				(pts
					(xy 98.1202 -97.0788) (xy 97.9678 -97.0788) (xy 97.9678 -96.4692) (xy 98.1202 -96.4692)
				)
			)
		)
		(zone
			(layer "F.Cu")
			(hatch none 0.5)
			(connect_pads
				(clearance 0)
			)
			(min_thickness 0.25)
			(keepout
				(tracks not_allowed)
				(vias allowed)
				(pads allowed)
				(copperpour not_allowed)
				(footprints allowed)
			)
			(placement
				(enabled no)
				(sheetname "")
			)
			(fill
				(thermal_gap 0.5)
				(thermal_bridge_width 0.5)
				(island_removal_mode 0)
			)
			(polygon
				(pts
					(xy 98.1202 -97.0788) (xy 97.9678 -97.0788) (xy 97.9678 -96.4692) (xy 98.1202 -96.4692)
				)
			)
		)
	)
	(footprint ""
		(layer "F.Cu")
		(at 30.34538 -19.14144 180)
		(property "Reference" "R1992"
			(at 0.508 4.91363 0)
			(unlocked yes)
			(layer "F.SilkS")
			(effects
				(font
					(size 0.7874 0.5842)
					(thickness 0.1524)
				)
			)
		)
		(property "Value" "VAL*"
			(at 0.02032 2.13233 180)
			(unlocked yes)
			(layer "F.Fab")
			(hide yes)
			(effects
				(font
					(size 0.7874 0.5842)
					(thickness 0.1524)
				)
			)
		)
		(property "Tolerance" "TOL*"
			(at 0.044704 3.05435 180)
			(unlocked yes)
			(layer "Cmts.User")
			(hide yes)
			(effects
				(font
					(size 0.7874 0.5842)
					(thickness 0.1524)
				)
			)
		)
		(property "User Part Number" "PARTNUM*"
			(at 0.02032 4.024884 180)
			(unlocked yes)
			(layer "Cmts.User")
			(hide yes)
			(effects
				(font
					(size 0.7874 0.5842)
					(thickness 0.1524)
				)
			)
		)
		(property "Device Type" "RESISTOR-G155-14701-01,4.7KOHMA"
			(at 0.008382 1.210564 180)
			(unlocked yes)
			(layer "F.Fab")
			(hide yes)
			(effects
				(font
					(size 0.7874 0.5842)
					(thickness 0.1524)
				)
			)
		)
		(duplicate_pad_numbers_are_jumpers no)
		(fp_line
			(start 1.143 0.5588)
			(end 1.143 -0.5588)
			(stroke
				(width 0.1)
				(type default)
			)
			(layer "F.SilkS")
		)
		(fp_line
			(start 1.143 -0.5588)
			(end -1.143 -0.5588)
			(stroke
				(width 0.1)
				(type default)
			)
			(layer "F.SilkS")
		)
		(fp_line
			(start -1.143 0.5588)
			(end 1.143 0.5588)
			(stroke
				(width 0.1)
				(type default)
			)
			(layer "F.SilkS")
		)
		(fp_line
			(start -1.143 -0.5588)
			(end -1.143 0.5588)
			(stroke
				(width 0.1)
				(type default)
			)
			(layer "F.SilkS")
		)
		(fp_rect
			(start 1.143 -0.5588)
			(end -1.143 0.5588)
			(stroke
				(width 0)
				(type default)
			)
			(fill no)
			(layer "F.CrtYd")
		)
		(fp_line
			(start 0.508 0.3048)
			(end 0.508 -0.3048)
			(stroke
				(width 0.1)
				(type default)
			)
			(layer "F.Fab")
		)
		(fp_line
			(start 0.508 -0.3048)
			(end -0.508 -0.3048)
			(stroke
				(width 0.1)
				(type default)
			)
			(layer "F.Fab")
		)
		(fp_line
			(start -0.508 0.3048)
			(end 0.508 0.3048)
			(stroke
				(width 0.1)
				(type default)
			)
			(layer "F.Fab")
		)
		(fp_line
			(start -0.508 -0.3048)
			(end -0.508 0.3048)
			(stroke
				(width 0.1)
				(type default)
			)
			(layer "F.Fab")
		)
		(pad "1" smd rect
			(at -0.5334 0 180)
			(size 0.7112 0.6096)
			(layers "F.Cu" "F.Mask" "F.Paste")
			(net "XP3R3V_FPGA")
		)
		(pad "2" smd rect
			(at 0.5334 0 180)
			(size 0.7112 0.6096)
			(layers "F.Cu" "F.Mask" "F.Paste")
			(net "SN_EEPROM_WP")
		)
		(zone
			(layer "F.Cu")
			(hatch none 0.5)
			(connect_pads
				(clearance 0)
			)
			(min_thickness 0.25)
			(keepout
				(tracks allowed)
				(vias not_allowed)
				(pads allowed)
				(copperpour not_allowed)
				(footprints allowed)
			)
			(placement
				(enabled no)
				(sheetname "")
			)
			(fill
				(thermal_gap 0.5)
				(thermal_bridge_width 0.5)
				(island_removal_mode 0)
			)
			(polygon
				(pts
					(xy 30.26918 -18.83664) (xy 30.42158 -18.83664) (xy 30.42158 -19.44624) (xy 30.26918 -19.44624)
				)
			)
		)
	)
)
